(kicad_pcb
	(version 20260206)
	(generator "pcbnew")
	(generator_version "10.0")
	(general
		(thickness 1.6)
		(legacy_teardrops no)
	)
	(paper "A4")
	(title_block
		(title "Bryce Canyon_F.DPB_16315-1-OCP.brd")
		(comment 1 "Bryce Canyon / footprints 671-676 of 2223")
	)
	(layers
		(0 "F.Cu" signal "TOP")
		(4 "In1.Cu" signal "L2GND")
		(6 "In2.Cu" signal "L3")
		(8 "In3.Cu" signal "L4GND")
		(10 "In4.Cu" signal "L5")
		(12 "In5.Cu" signal "L6VCC")
		(14 "In6.Cu" signal "L7VCC")
		(16 "In7.Cu" signal "L8")
		(18 "In8.Cu" signal "L9GND")
		(20 "In9.Cu" signal "L10")
		(22 "In10.Cu" signal "L11GND")
		(2 "B.Cu" signal "BOTTOM")
		(9 "F.Adhes" user "F.Adhesive")
		(11 "B.Adhes" user "B.Adhesive")
		(13 "F.Paste" user "Package Geometry/Pastemask Top")
		(15 "B.Paste" user "Package Geometry/Pastemask Bottom")
		(5 "F.SilkS" user "Ref Des/Silkscreen Top")
		(7 "B.SilkS" user "Ref Des/Silkscreen Bottom")
		(1 "F.Mask" user "Board Geometry/Soldermask Top")
		(3 "B.Mask" user "Board Geometry/Soldermask Bottom")
		(17 "Dwgs.User" user "User.Drawings")
		(19 "Cmts.User" user "User.Comments")
		(21 "Eco1.User" user "User.Eco1")
		(23 "Eco2.User" user "User.Eco2")
		(25 "Edge.Cuts" user "Board Geometry/Outline")
		(27 "Margin" user)
		(31 "F.CrtYd" user "Package Geometry/Place Bound Top")
		(29 "B.CrtYd" user "Package Geometry/Place Bound Bottom")
		(35 "F.Fab" user "Ref Des/Assembly Top")
		(33 "B.Fab" user "Ref Des/Assembly Bottom")
	)
	(footprint ""
		(layer "F.Cu")
		(at 426.120052 -188.954918 180)
		(property "Reference" "C318"
			(at 0 0 180)
			(layer "F.SilkS")
			(hide yes)
			(effects
				(font
					(size 1.27 1.27)
				)
			)
		)
		(property "Value" "SC4D7U25V5KX-1-GP"
			(at -0.0762 -6.1214 180)
			(unlocked yes)
			(layer "F.Fab")
			(hide yes)
			(effects
				(font
					(size 1.016 1.016)
					(thickness 0.1524)
				)
			)
		)
		(property "Device Type" "C805H58"
			(at -0.0762 -8.1534 180)
			(unlocked yes)
			(layer "F.Fab")
			(hide yes)
			(effects
				(font
					(size 1.016 1.016)
					(thickness 0.1524)
				)
			)
		)
		(duplicate_pad_numbers_are_jumpers no)
		(fp_line
			(start 0.635 0)
			(end -0.635 0)
			(stroke
				(width 0.508)
				(type default)
			)
			(layer "F.SilkS")
		)
		(fp_rect
			(start -0.9652 1.778)
			(end 0.9652 -1.778)
			(stroke
				(width 0)
				(type default)
			)
			(fill no)
			(layer "F.CrtYd")
		)
		(fp_poly
			(pts
				(xy -0.9652 -1.778) (xy 0.9652 -1.778) (xy 0.9652 1.778) (xy -0.9652 1.778)
			)
			(stroke
				(width 0)
				(type default)
			)
			(fill no)
			(layer "F.Fab")
		)
		(pad "1" smd rect
			(at 0 -0.9652 180)
			(size 1.397 1.143)
			(layers "F.Cu" "F.Mask" "F.Paste")
			(net "P12V_HDD21")
		)
		(pad "2" smd rect
			(at 0 0.9652 180)
			(size 1.397 1.143)
			(layers "F.Cu" "F.Mask" "F.Paste")
			(net "GND")
		)
	)
	(footprint ""
		(layer "F.Cu")
		(at 252.386846 -261.326122 180)
		(property "Reference" "R427"
			(at 0 0 180)
			(layer "F.SilkS")
			(hide yes)
			(effects
				(font
					(size 1.27 1.27)
				)
			)
		)
		(property "Value" "1KR2F-3-GP"
			(at 0.064008 -3.993896 180)
			(unlocked yes)
			(layer "F.Fab")
			(hide yes)
			(effects
				(font
					(size 1.016 1.016)
					(thickness 0.1524)
				)
			)
		)
		(property "Device Type" "R402H16"
			(at 0.064008 -5.517896 180)
			(unlocked yes)
			(layer "F.Fab")
			(hide yes)
			(effects
				(font
					(size 1.016 1.016)
					(thickness 0.1524)
				)
			)
		)
		(duplicate_pad_numbers_are_jumpers no)
		(fp_line
			(start 0.508 -0.9398)
			(end -0.508 -0.9398)
			(stroke
				(width 0.1524)
				(type default)
			)
			(layer "F.SilkS")
		)
		(fp_line
			(start -0.508 -0.9398)
			(end -0.508 0.9398)
			(stroke
				(width 0.1524)
				(type default)
			)
			(layer "F.SilkS")
		)
		(fp_rect
			(start -0.508 0.9398)
			(end 0.508 -0.9398)
			(stroke
				(width 0)
				(type default)
			)
			(fill no)
			(layer "F.CrtYd")
		)
		(fp_rect
			(start -0.508 0.9398)
			(end 0.508 -0.9398)
			(stroke
				(width 0)
				(type default)
			)
			(fill no)
			(layer "F.Fab")
		)
		(pad "1" smd custom
			(at 0 -0.4445 180)
			(size 0.1397 0.1397)
			(layers "F.Cu" "F.Mask" "F.Paste")
			(net "P3V3_STBY_A")
			(options
				(clearance outline)
				(anchor circle)
			)
			(primitives
				(gr_poly
					(pts
						(arc
							(start -0.1778 -0.2794)
							(mid -0.249642 -0.249642)
							(end -0.2794 -0.1778)
						)
						(arc
							(start -0.2794 0.1778)
							(mid -0.249642 0.249642)
							(end -0.1778 0.2794)
						)
						(arc
							(start 0.1778 0.2794)
							(mid 0.249642 0.249642)
							(end 0.2794 0.1778)
						)
						(arc
							(start 0.2794 -0.1778)
							(mid 0.249642 -0.249642)
							(end 0.1778 -0.2794)
						)
					)
					(width 0)
					(fill yes)
				)
			)
		)
		(pad "2" smd custom
			(at 0 0.4445 180)
			(size 0.1397 0.1397)
			(layers "F.Cu" "F.Mask" "F.Paste")
			(net "I2C_DRIVE_A_INS_SDA")
			(options
				(clearance outline)
				(anchor circle)
			)
			(primitives
				(gr_poly
					(pts
						(arc
							(start -0.1778 -0.2794)
							(mid -0.249642 -0.249642)
							(end -0.2794 -0.1778)
						)
						(arc
							(start -0.2794 0.1778)
							(mid -0.249642 0.249642)
							(end -0.1778 0.2794)
						)
						(arc
							(start 0.1778 0.2794)
							(mid 0.249642 0.249642)
							(end 0.2794 0.1778)
						)
						(arc
							(start 0.2794 -0.1778)
							(mid 0.249642 -0.249642)
							(end 0.1778 -0.2794)
						)
					)
					(width 0)
					(fill yes)
				)
			)
		)
	)
	(footprint ""
		(layer "F.Cu")
		(at 469.370918 -162.644074 90)
		(property "Reference" "D23"
			(at 0 0 90)
			(layer "F.SilkS")
			(hide yes)
			(effects
				(font
					(size 1.27 1.27)
				)
			)
		)
		(property "Value" "RB551V30-GP"
			(at 0 -6.7818 90)
			(unlocked yes)
			(layer "F.Fab")
			(hide yes)
			(effects
				(font
					(size 1.016 1.016)
					(thickness 0.1524)
				)
			)
		)
		(property "Device Type" "SOD323AKH38"
			(at 0 -8.6868 90)
			(unlocked yes)
			(layer "F.Fab")
			(hide yes)
			(effects
				(font
					(size 1.016 1.016)
					(thickness 0.1524)
				)
			)
		)
		(duplicate_pad_numbers_are_jumpers no)
		(fp_line
			(start 0.889 -1.9304)
			(end 0.889 2.159)
			(stroke
				(width 0.1524)
				(type default)
			)
			(layer "F.SilkS")
		)
		(fp_line
			(start -0.889 -1.9304)
			(end 0.889 -1.9304)
			(stroke
				(width 0.1524)
				(type default)
			)
			(layer "F.SilkS")
		)
		(fp_line
			(start 0.762 2.0574)
			(end -0.762 2.0574)
			(stroke
				(width 0.508)
				(type default)
			)
			(layer "F.SilkS")
		)
		(fp_line
			(start 0.889 2.159)
			(end -0.889 2.159)
			(stroke
				(width 0.1524)
				(type default)
			)
			(layer "F.SilkS")
		)
		(fp_line
			(start -0.889 2.159)
			(end -0.889 -1.9304)
			(stroke
				(width 0.1524)
				(type default)
			)
			(layer "F.SilkS")
		)
		(fp_rect
			(start -1.016 2.3114)
			(end 1.016 -2.0066)
			(stroke
				(width 0)
				(type default)
			)
			(fill no)
			(layer "F.CrtYd")
		)
		(fp_poly
			(pts
				(xy -1.016 -2.0066) (xy 1.016 -2.0066) (xy 1.016 2.3114) (xy -1.016 2.3114)
			)
			(stroke
				(width 0)
				(type default)
			)
			(fill no)
			(layer "F.Fab")
		)
		(pad "A" smd rect
			(at 0 -1.143 90)
			(size 0.5588 1.016)
			(layers "F.Cu" "F.Mask" "F.Paste")
			(net "SW_HDD_R23")
		)
		(pad "K" smd rect
			(at 0 1.143 90)
			(size 0.5588 1.016)
			(layers "F.Cu" "F.Mask" "F.Paste")
			(net "SW_HDD_N23")
		)
	)
	(footprint ""
		(layer "F.Cu")
		(at 264.16 -278.13)
		(property "Reference" "U10"
			(at 0 0 0)
			(layer "F.SilkS")
			(hide yes)
			(effects
				(font
					(size 1.27 1.27)
				)
			)
		)
		(property "Value" "TCA9555PWR-GP"
			(at 0 -6.9342 0)
			(unlocked yes)
			(layer "F.Fab")
			(hide yes)
			(effects
				(font
					(size 1.016 1.016)
					(thickness 0.1524)
				)
			)
		)
		(property "Device Type" "TSOIC24H48"
			(at 0 -8.5852 0)
			(unlocked yes)
			(layer "F.Fab")
			(hide yes)
			(effects
				(font
					(size 1.016 1.016)
					(thickness 0.1524)
				)
			)
		)
		(duplicate_pad_numbers_are_jumpers no)
		(fp_line
			(start -4.2291 -1.397)
			(end 3.81 -1.397)
			(stroke
				(width 0.1524)
				(type default)
			)
			(layer "F.SilkS")
		)
		(fp_line
			(start -4.2291 -0.8001)
			(end -3.429 0)
			(stroke
				(width 0.1524)
				(type default)
			)
			(layer "F.SilkS")
		)
		(fp_line
			(start -4.2291 3.937)
			(end -4.2291 -1.397)
			(stroke
				(width 0.1524)
				(type default)
			)
			(layer "F.SilkS")
		)
		(fp_line
			(start -4.22656 3.81)
			(end -4.2291 1.397)
			(stroke
				(width 0.508)
				(type default)
			)
			(layer "F.SilkS")
		)
		(fp_line
			(start -3.429 0)
			(end -4.2291 0.8001)
			(stroke
				(width 0.1524)
				(type default)
			)
			(layer "F.SilkS")
		)
		(fp_line
			(start 3.81 -1.397)
			(end 3.81 1.397)
			(stroke
				(width 0.1524)
				(type default)
			)
			(layer "F.SilkS")
		)
		(fp_line
			(start 3.81 1.397)
			(end -4.2291 1.397)
			(stroke
				(width 0.1524)
				(type default)
			)
			(layer "F.SilkS")
		)
		(fp_poly
			(pts
				(xy -3.90652 -1.8542) (xy 3.90652 -1.8542) (xy 3.90652 1.8542) (xy -3.90652 1.8542)
			)
			(stroke
				(width 0)
				(type default)
			)
			(fill yes)
			(layer "F.SilkS")
		)
		(fp_poly
			(pts
				(xy -4.2164 3.81) (xy 4.2164 3.81) (xy 4.22656 -3.81) (xy -4.2164 -3.81)
			)
			(stroke
				(width 0)
				(type default)
			)
			(fill no)
			(layer "F.CrtYd")
		)
		(fp_poly
			(pts
				(xy -4.22656 -3.81) (xy 4.22656 -3.81) (xy 4.22656 3.81) (xy -4.22656 3.81)
			)
			(stroke
				(width 0)
				(type default)
			)
			(fill no)
			(layer "F.Fab")
		)
		(pad "1" smd rect
			(at -3.57632 2.8194)
			(size 0.3556 1.524)
			(layers "F.Cu" "F.Mask" "F.Paste")
			(net "IO_EXP0_INT_N")
		)
		(pad "2" smd rect
			(at -2.92608 2.8194)
			(size 0.3556 1.524)
			(layers "F.Cu" "F.Mask" "F.Paste")
			(net "IO_EXP0_HDD_FAULT_A1")
		)
		(pad "3" smd rect
			(at -2.27584 2.8194)
			(size 0.3556 1.524)
			(layers "F.Cu" "F.Mask" "F.Paste")
			(net "IO_EXP0_HDD_FAULT_A2")
		)
		(pad "4" smd rect
			(at -1.6256 2.8194)
			(size 0.3556 1.524)
			(layers "F.Cu" "F.Mask" "F.Paste")
			(net "DRIVE_A_0_FLT_LED")
		)
		(pad "5" smd rect
			(at -0.97536 2.8194)
			(size 0.3556 1.524)
			(layers "F.Cu" "F.Mask" "F.Paste")
			(net "DRIVE_A_1_FLT_LED")
		)
		(pad "6" smd rect
			(at -0.32512 2.8194)
			(size 0.3556 1.524)
			(layers "F.Cu" "F.Mask" "F.Paste")
			(net "DRIVE_A_2_FLT_LED")
		)
		(pad "7" smd rect
			(at 0.32512 2.8194)
			(size 0.3556 1.524)
			(layers "F.Cu" "F.Mask" "F.Paste")
			(net "DRIVE_A_3_FLT_LED")
		)
		(pad "8" smd rect
			(at 0.97536 2.8194)
			(size 0.3556 1.524)
			(layers "F.Cu" "F.Mask" "F.Paste")
			(net "DRIVE_A_4_FLT_LED")
		)
		(pad "9" smd rect
			(at 1.6256 2.8194)
			(size 0.3556 1.524)
			(layers "F.Cu" "F.Mask" "F.Paste")
			(net "DRIVE_A_5_FLT_LED")
		)
		(pad "10" smd rect
			(at 2.27584 2.8194)
			(size 0.3556 1.524)
			(layers "F.Cu" "F.Mask" "F.Paste")
			(net "DRIVE_A_6_FLT_LED")
		)
		(pad "11" smd rect
			(at 2.92608 2.8194)
			(size 0.3556 1.524)
			(layers "F.Cu" "F.Mask" "F.Paste")
			(net "DRIVE_A_7_FLT_LED")
		)
		(pad "12" smd rect
			(at 3.57632 2.8194)
			(size 0.3556 1.524)
			(layers "F.Cu" "F.Mask" "F.Paste")
			(net "GND")
		)
		(pad "13" smd rect
			(at 3.57632 -2.8194)
			(size 0.3556 1.524)
			(layers "F.Cu" "F.Mask" "F.Paste")
			(net "DRIVE_A_8_FLT_LED")
		)
		(pad "14" smd rect
			(at 2.92608 -2.8194)
			(size 0.3556 1.524)
			(layers "F.Cu" "F.Mask" "F.Paste")
			(net "DRIVE_A_9_FLT_LED")
		)
		(pad "15" smd rect
			(at 2.27584 -2.8194)
			(size 0.3556 1.524)
			(layers "F.Cu" "F.Mask" "F.Paste")
			(net "DRIVE_A_10_FLT_LED")
		)
		(pad "16" smd rect
			(at 1.6256 -2.8194)
			(size 0.3556 1.524)
			(layers "F.Cu" "F.Mask" "F.Paste")
			(net "DRIVE_A_11_FLT_LED")
		)
		(pad "17" smd rect
			(at 0.97536 -2.8194)
			(size 0.3556 1.524)
			(layers "F.Cu" "F.Mask" "F.Paste")
			(net "DRIVE_A_12_FLT_LED")
		)
		(pad "18" smd rect
			(at 0.32512 -2.8194)
			(size 0.3556 1.524)
			(layers "F.Cu" "F.Mask" "F.Paste")
			(net "DRIVE_A_13_FLT_LED")
		)
		(pad "19" smd rect
			(at -0.32512 -2.8194)
			(size 0.3556 1.524)
			(layers "F.Cu" "F.Mask" "F.Paste")
			(net "DRIVE_A_14_FLT_LED")
		)
		(pad "20" smd rect
			(at -0.97536 -2.8194)
			(size 0.3556 1.524)
			(layers "F.Cu" "F.Mask" "F.Paste")
			(net "DRIVE_A_15_FLT_LED")
		)
		(pad "21" smd rect
			(at -1.6256 -2.8194)
			(size 0.3556 1.524)
			(layers "F.Cu" "F.Mask" "F.Paste")
			(net "IO_EXP0_HDD_FAULT_A0")
		)
		(pad "22" smd rect
			(at -2.27584 -2.8194)
			(size 0.3556 1.524)
			(layers "F.Cu" "F.Mask" "F.Paste")
			(net "IO_EXP0_LED_SCL")
		)
		(pad "23" smd rect
			(at -2.92608 -2.8194)
			(size 0.3556 1.524)
			(layers "F.Cu" "F.Mask" "F.Paste")
			(net "IO_EXP0_LED_SDA")
		)
		(pad "24" smd rect
			(at -3.57632 -2.8194)
			(size 0.3556 1.524)
			(layers "F.Cu" "F.Mask" "F.Paste")
			(net "P3V3_STBY_A")
		)
	)
	(footprint ""
		(layer "F.Cu")
		(at 349.431102 -180.064918 -90)
		(property "Reference" "R571"
			(at 0 0 270)
			(layer "F.SilkS")
			(hide yes)
			(effects
				(font
					(size 1.27 1.27)
				)
			)
		)
		(property "Value" "220R3F-1-GP"
			(at -0.0254 -2.5146 270)
			(unlocked yes)
			(layer "F.Fab")
			(hide yes)
			(effects
				(font
					(size 1.016 1.016)
					(thickness 0.1524)
				)
			)
		)
		(property "Device Type" "R603H22"
			(at -0.0254 -4.0386 270)
			(unlocked yes)
			(layer "F.Fab")
			(hide yes)
			(effects
				(font
					(size 1.016 1.016)
					(thickness 0.1524)
				)
			)
		)
		(duplicate_pad_numbers_are_jumpers no)
		(fp_line
			(start -0.4826 0)
			(end -0.2032 0)
			(stroke
				(width 0.2032)
				(type default)
			)
			(layer "F.SilkS")
		)
		(fp_line
			(start 0.2032 0)
			(end 0.4826 0)
			(stroke
				(width 0.2032)
				(type default)
			)
			(layer "F.SilkS")
		)
		(fp_rect
			(start -0.5842 1.3335)
			(end 0.5842 -1.3335)
			(stroke
				(width 0)
				(type default)
			)
			(fill no)
			(layer "F.CrtYd")
		)
		(fp_rect
			(start -0.5842 1.3335)
			(end 0.5842 -1.3335)
			(stroke
				(width 0)
				(type default)
			)
			(fill no)
			(layer "F.Fab")
		)
		(pad "1" smd custom
			(at 0 -0.762 270)
			(size 0.2159 0.2159)
			(layers "F.Cu" "F.Mask" "F.Paste")
			(net "HDD_PRSNT_19")
			(options
				(clearance outline)
				(anchor circle)
			)
			(primitives
				(gr_poly
					(pts
						(arc
							(start -0.3302 -0.4318)
							(mid -0.402042 -0.402042)
							(end -0.4318 -0.3302)
						)
						(arc
							(start -0.4318 0.3302)
							(mid -0.402042 0.402042)
							(end -0.3302 0.4318)
						)
						(arc
							(start 0.3302 0.4318)
							(mid 0.402042 0.402042)
							(end 0.4318 0.3302)
						)
						(arc
							(start 0.4318 -0.3302)
							(mid 0.402042 -0.402042)
							(end 0.3302 -0.4318)
						)
					)
					(width 0)
					(fill yes)
				)
			)
		)
		(pad "2" smd custom
			(at 0 0.762 270)
			(size 0.2159 0.2159)
			(layers "F.Cu" "F.Mask" "F.Paste")
			(net "DRIVE_A_19_INS")
			(options
				(clearance outline)
				(anchor circle)
			)
			(primitives
				(gr_poly
					(pts
						(arc
							(start -0.3302 -0.4318)
							(mid -0.402042 -0.402042)
							(end -0.4318 -0.3302)
						)
						(arc
							(start -0.4318 0.3302)
							(mid -0.402042 0.402042)
							(end -0.3302 0.4318)
						)
						(arc
							(start 0.3302 0.4318)
							(mid 0.402042 0.402042)
							(end 0.4318 0.3302)
						)
						(arc
							(start 0.4318 -0.3302)
							(mid 0.402042 -0.402042)
							(end 0.3302 -0.4318)
						)
					)
					(width 0)
					(fill yes)
				)
			)
		)
	)
	(footprint ""
		(layer "F.Cu")
		(at 274.066 -284.734 180)
		(property "Reference" "R114"
			(at 0 0 180)
			(layer "F.SilkS")
			(hide yes)
			(effects
				(font
					(size 1.27 1.27)
				)
			)
		)
		(property "Value" "0R2J-2-GP"
			(at 0.064008 -3.993896 180)
			(unlocked yes)
			(layer "F.Fab")
			(hide yes)
			(effects
				(font
					(size 1.016 1.016)
					(thickness 0.1524)
				)
			)
		)
		(property "Device Type" "R402H16"
			(at 0.064008 -5.517896 180)
			(unlocked yes)
			(layer "F.Fab")
			(hide yes)
			(effects
				(font
					(size 1.016 1.016)
					(thickness 0.1524)
				)
			)
		)
		(duplicate_pad_numbers_are_jumpers no)
		(fp_line
			(start 0.508 -0.9398)
			(end -0.508 -0.9398)
			(stroke
				(width 0.1524)
				(type default)
			)
			(layer "F.SilkS")
		)
		(fp_line
			(start -0.508 -0.9398)
			(end -0.508 0.9398)
			(stroke
				(width 0.1524)
				(type default)
			)
			(layer "F.SilkS")
		)
		(fp_rect
			(start -0.508 0.9398)
			(end 0.508 -0.9398)
			(stroke
				(width 0)
				(type default)
			)
			(fill no)
			(layer "F.CrtYd")
		)
		(fp_rect
			(start -0.508 0.9398)
			(end 0.508 -0.9398)
			(stroke
				(width 0)
				(type default)
			)
			(fill no)
			(layer "F.Fab")
		)
		(pad "1" smd custom
			(at 0 -0.4445 180)
			(size 0.1397 0.1397)
			(layers "F.Cu" "F.Mask" "F.Paste")
			(net "IO_EXP1_LED_SCL")
			(options
				(clearance outline)
				(anchor circle)
			)
			(primitives
				(gr_poly
					(pts
						(arc
							(start -0.1778 -0.2794)
							(mid -0.249642 -0.249642)
							(end -0.2794 -0.1778)
						)
						(arc
							(start -0.2794 0.1778)
							(mid -0.249642 0.249642)
							(end -0.1778 0.2794)
						)
						(arc
							(start 0.1778 0.2794)
							(mid 0.249642 0.249642)
							(end 0.2794 0.1778)
						)
						(arc
							(start 0.2794 -0.1778)
							(mid 0.249642 -0.249642)
							(end 0.1778 -0.2794)
						)
					)
					(width 0)
					(fill yes)
				)
			)
		)
		(pad "2" smd custom
			(at 0 0.4445 180)
			(size 0.1397 0.1397)
			(layers "F.Cu" "F.Mask" "F.Paste")
			(net "I2C_DRIVE_A_FLT_LED_SCL")
			(options
				(clearance outline)
				(anchor circle)
			)
			(primitives
				(gr_poly
					(pts
						(arc
							(start -0.1778 -0.2794)
							(mid -0.249642 -0.249642)
							(end -0.2794 -0.1778)
						)
						(arc
							(start -0.2794 0.1778)
							(mid -0.249642 0.249642)
							(end -0.1778 0.2794)
						)
						(arc
							(start 0.1778 0.2794)
							(mid 0.249642 0.249642)
							(end 0.2794 0.1778)
						)
						(arc
							(start 0.2794 -0.1778)
							(mid 0.249642 -0.249642)
							(end 0.1778 -0.2794)
						)
					)
					(width 0)
					(fill yes)
				)
			)
		)
	)
)
